FILE_TYPE = CONNECTIVITY;
{Allegro Design Entry HDL 17.2-2016 S081 (4005846) 1/11/2022}
"PAGE_NUMBER" = 44;
0"NC";
1"M_H_CPU1_SA_DQ<31:0>";
2"M_H_CPU1_SB_DQ<31:0>";
3"M_H_CPU1_SA_CB<7:0>";
4"M_H_CPU1_SB_CB<7:0>";
5"M_H_CPU1_SA_DQS_DP<9:0>";
6"M_H_CPU1_SB_DQS_DP<9:0>";
7"M_H_CPU1_SA_CA<6:0>";
8"M_H_CPU1_SB_CA<6:0>";
9"M_H_CPU1_SA_DQS_DN<9:0>";
10"M_H_CPU1_SB_DQS_DN<9:0>";
11"M_H_CPU1_ALERT_N";
12"TP_M_H_CPU1_SA_TEST39H";
13"M_H_CPU1_ALERT_R_N";
14"M_H_CPU1_CLK_DN<0>";
15"M_H_CPU1_CLK_DP<0>";
16"M_H_CPU1_SA_CS_N<0>";
17"M_H_CPU1_SA_CS_N<1>";
18"M_H_CPU1_SA_RSP<0>";
19"M_H_CPU1_SA_PAR";
20"M_H_CPU1_SB_CS_N<1>";
21"M_H_CPU1_SB_CS_N<0>";
22"M_H_CPU1_SB_RSP<0>";
23"M_H_CPU1_SB_PAR";
24"M_H_CPU1_RESET_N";
25"M_H_CPU1_SB_CA<6>";
26"M_H_CPU1_SB_DQS_DP<9>";
27"M_H_CPU1_SB_DQS_DP<8>";
28"M_H_CPU1_SB_DQS_DN<9>";
29"M_H_CPU1_SB_DQS_DN<8>";
30"M_H_CPU1_SA_CA<6>";
31"M_H_CPU1_SB_CA<5>";
32"M_H_CPU1_SA_CA<5>";
33"M_H_CPU1_SB_CA<4>";
34"M_H_CPU1_SA_CA<4>";
35"M_H_CPU1_SB_CA<3>";
36"M_H_CPU1_SA_CA<3>";
37"M_H_CPU1_SB_CA<2>";
38"M_H_CPU1_SA_CA<2>";
39"M_H_CPU1_SB_CA<1>";
40"M_H_CPU1_SA_CA<1>";
41"M_H_CPU1_SB_CA<0>";
42"M_H_CPU1_SA_CA<0>";
43"M_H_CPU1_SB_DQS_DP<7>";
44"M_H_CPU1_SB_DQS_DP<6>";
45"M_H_CPU1_SB_DQS_DP<5>";
46"M_H_CPU1_SB_DQS_DP<4>";
47"M_H_CPU1_SA_DQS_DP<9>";
48"M_H_CPU1_SB_DQS_DP<3>";
49"M_H_CPU1_SB_DQS_DN<7>";
50"M_H_CPU1_SA_DQS_DP<8>";
51"M_H_CPU1_SB_DQS_DP<2>";
52"M_H_CPU1_SB_DQS_DN<6>";
53"M_H_CPU1_SB_DQS_DP<1>";
54"M_H_CPU1_SB_DQS_DN<5>";
55"M_H_CPU1_SB_DQS_DP<0>";
56"M_H_CPU1_SB_DQS_DN<4>";
57"M_H_CPU1_SA_DQS_DN<9>";
58"M_H_CPU1_SB_DQS_DN<3>";
59"M_H_CPU1_SA_DQS_DN<8>";
60"M_H_CPU1_SB_DQS_DN<2>";
61"M_H_CPU1_SB_DQS_DN<1>";
62"M_H_CPU1_SB_DQS_DN<0>";
63"M_H_CPU1_SA_DQS_DN<1>";
64"M_H_CPU1_SA_DQS_DN<0>";
65"M_H_CPU1_SA_DQS_DP<7>";
66"M_H_CPU1_SA_DQS_DP<6>";
67"M_H_CPU1_SA_DQS_DP<5>";
68"M_H_CPU1_SA_DQS_DP<4>";
69"M_H_CPU1_SA_DQS_DP<3>";
70"M_H_CPU1_SA_DQS_DN<7>";
71"M_H_CPU1_SA_DQS_DP<2>";
72"M_H_CPU1_SA_DQS_DN<6>";
73"M_H_CPU1_SA_DQS_DP<1>";
74"M_H_CPU1_SA_DQS_DN<5>";
75"M_H_CPU1_SA_DQS_DP<0>";
76"M_H_CPU1_SA_DQS_DN<4>";
77"M_H_CPU1_SA_DQS_DN<3>";
78"M_H_CPU1_SA_DQS_DN<2>";
79"M_H_CPU1_SB_CB<7>";
80"M_H_CPU1_SB_CB<6>";
81"M_H_CPU1_SB_CB<5>";
82"M_H_CPU1_SB_CB<4>";
83"M_H_CPU1_SB_CB<3>";
84"M_H_CPU1_SB_CB<2>";
85"M_H_CPU1_SA_CB<7>";
86"M_H_CPU1_SB_CB<1>";
87"M_H_CPU1_SA_CB<6>";
88"M_H_CPU1_SB_CB<0>";
89"M_H_CPU1_SA_CB<5>";
90"M_H_CPU1_SB_DQ<30>";
91"M_H_CPU1_SA_CB<4>";
92"M_H_CPU1_SA_CB<3>";
93"M_H_CPU1_SA_CB<2>";
94"M_H_CPU1_SA_CB<1>";
95"M_H_CPU1_SA_CB<0>";
96"M_H_CPU1_SB_DQ<19>";
97"M_H_CPU1_SB_DQ<29>";
98"M_H_CPU1_SB_DQ<28>";
99"M_H_CPU1_SB_DQ<27>";
100"M_H_CPU1_SB_DQ<26>";
101"M_H_CPU1_SB_DQ<25>";
102"M_H_CPU1_SB_DQ<24>";
103"M_H_CPU1_SB_DQ<23>";
104"M_H_CPU1_SB_DQ<22>";
105"M_H_CPU1_SB_DQ<21>";
106"M_H_CPU1_SB_DQ<20>";
107"M_H_CPU1_SB_DQ<31>";
108"M_H_CPU1_SB_DQ<9>";
109"M_H_CPU1_SB_DQ<8>";
110"M_H_CPU1_SB_DQ<7>";
111"M_H_CPU1_SB_DQ<6>";
112"M_H_CPU1_SB_DQ<5>";
113"M_H_CPU1_SB_DQ<4>";
114"M_H_CPU1_SB_DQ<18>";
115"M_H_CPU1_SB_DQ<3>";
116"M_H_CPU1_SB_DQ<17>";
117"M_H_CPU1_SB_DQ<2>";
118"M_H_CPU1_SB_DQ<16>";
119"M_H_CPU1_SB_DQ<1>";
120"M_H_CPU1_SB_DQ<15>";
121"M_H_CPU1_SB_DQ<14>";
122"M_H_CPU1_SB_DQ<13>";
123"M_H_CPU1_SB_DQ<12>";
124"M_H_CPU1_SB_DQ<11>";
125"M_H_CPU1_SB_DQ<10>";
126"M_H_CPU1_SA_DQ<25>";
127"M_H_CPU1_SA_DQ<24>";
128"M_H_CPU1_SA_DQ<23>";
129"M_H_CPU1_SA_DQ<22>";
130"M_H_CPU1_SA_DQ<21>";
131"M_H_CPU1_SA_DQ<20>";
132"M_H_CPU1_SA_DQ<31>";
133"M_H_CPU1_SA_DQ<30>";
134"M_H_CPU1_SB_DQ<0>";
135"M_H_CPU1_SA_DQ<19>";
136"M_H_CPU1_SA_DQ<18>";
137"M_H_CPU1_SA_DQ<29>";
138"M_H_CPU1_SA_DQ<17>";
139"M_H_CPU1_SA_DQ<28>";
140"M_H_CPU1_SA_DQ<16>";
141"M_H_CPU1_SA_DQ<27>";
142"M_H_CPU1_SA_DQ<15>";
143"M_H_CPU1_SA_DQ<26>";
144"M_H_CPU1_SA_DQ<14>";
145"M_H_CPU1_SA_DQ<13>";
146"M_H_CPU1_SA_DQ<9>";
147"M_H_CPU1_SA_DQ<12>";
148"M_H_CPU1_SA_DQ<8>";
149"M_H_CPU1_SA_DQ<11>";
150"M_H_CPU1_SA_DQ<7>";
151"M_H_CPU1_SA_DQ<10>";
152"M_H_CPU1_SA_DQ<6>";
153"M_H_CPU1_SA_DQ<5>";
154"M_H_CPU1_SA_DQ<4>";
155"M_H_CPU1_SA_DQ<3>";
156"M_H_CPU1_SA_DQ<2>";
157"M_H_CPU1_SA_DQ<1>";
158"M_H_CPU1_SA_DQ<0>";
%"GENOA_SP5"
"8","(-4625,3525)","0","pure_quanta","I159";
;
LOCATION"U26"
$SEC"8"
CDS_SEC"8"
PART_TYPE"SMLF"
MATERIAL"IO"
VALUE"SOCKET6096_13568-001"
PART_NUMBER"DGA^6000030"
CDS_LIB"pure_quanta"
CDS_LMAN_SYM_OUTLINE"-650,2525,650,-2525"
NEEDS_NO_SIZE"TRUE";
"TEST39H"
$PN"BF14"12;
"MH1_CLK_L"
$PN"BG12"0;
"MH1_CLK_H"
$PN"BF13"0;
"MH0_CLK_L"
$PN"BD13"14;
"MH0_CLK_H"
$PN"BC12"15;
"MHB_PAR"
$PN"BL14"23;
"MHA_PAR"
$PN"BC14"19;
"MHB_DQS_H9"
$PN"BV13"26;
"MHA_CHECK5"
$PN"AP14"89;
"MHA_DATA14"
$PN"T13"144;
"MHA_DATA25"
$PN"AD14"126;
"MHA_DQS_L1"
$PN"P13"63;
"MHB0_CS_L1"
$PN"BN12"20;
"MHB1_CS_L0"
$PN"BL12"0;
"MHB_DATA30"
$PN"DE12"90;
"MHB_DQS_H8"
$PN"DD14"27;
"MHA_CHECK4"
$PN"AN12"91;
"MHA_DATA13"
$PN"T14"145;
"MHA_DATA24"
$PN"AC12"127;
"MHA_DQS_L0"
$PN"H13"64;
"MHB0_CS_L0"
$PN"BM14"21;
"MHB_DQS_H7"
$PN"CV14"43;
"MHA_CHECK3"
$PN"AL14"92;
"MHA_DATA9"
$PN"M14"146;
"MHA_DATA12"
$PN"R12"147;
"MHA_DATA23"
$PN"AC14"128;
"MHB_DATA9"
$PN"CJ14"108;
"MHB_DQS_H6"
$PN"CM14"44;
"MHA_CHECK2"
$PN"AK13"93;
"MHA_DATA8"
$PN"L12"148;
"MHA_DATA11"
$PN"N14"149;
"MHA_DATA22"
$PN"AB13"129;
"MHB_DATA8"
$PN"CH13"109;
"MHB_DQS_H5"
$PN"CF14"45;
"MHB_DQS_L9"
$PN"BW12"28;
"MHA_CHECK1"
$PN"AK14"94;
"MHA_DATA7"
$PN"L14"150;
"MHA_DATA10"
$PN"M13"151;
"MHA_DATA21"
$PN"AB14"130;
"MHB_DATA7"
$PN"CH14"110;
"MHB_DQS_H4"
$PN"BY14"46;
"MHB_DQS_L8"
$PN"DC14"29;
"MHA1_CS_L1"
$PN"AW14"0;
"MHA_CHECK0"
$PN"AJ12"95;
"MHA_DATA6"
$PN"K13"152;
"MHA_DATA20"
$PN"AA12"131;
"MHA_DATA31"
$PN"AJ14"132;
"MHA_DQS_H9"
$PN"AN14"47;
"MHB_DATA6"
$PN"CG12"111;
"MHB_DQS_H3"
$PN"DB13"48;
"MHB_DQS_L7"
$PN"CU14"49;
"MHA0_CS_L1"
$PN"AV14"17;
"MHA1_CS_L0"
$PN"AV13"0;
"MHA_DATA5"
$PN"K14"153;
"MHA_DATA30"
$PN"AH13"133;
"MHA_DQS_H8"
$PN"AG14"50;
"MHB_DATA5"
$PN"CG14"112;
"MHB_DATA19"
$PN"CT14"96;
"MHB_DQS_H2"
$PN"CT13"51;
"MHB_DQS_L6"
$PN"CL14"52;
"MHA0_CS_L0"
$PN"AU12"16;
"MHA_DATA4"
$PN"J12"154;
"MHA_DQS_H7"
$PN"AA14"65;
"MHB_CA6"
$PN"BK13"25;
"MHB_DATA4"
$PN"CF13"113;
"MHB_DATA18"
$PN"CR12"114;
"MHB_DATA29"
$PN"DE14"97;
"MHB_DQS_H1"
$PN"CK13"53;
"MHB_DQS_L5"
$PN"CE14"54;
"MHA_CA6"
$PN"BB14"30;
"MHA_DATA3"
$PN"G14"155;
"MHA_DQS_H6"
$PN"R14"66;
"MHB1_RSP_L"
$PN"BR12"0;
"MHB_CA5"
$PN"BK14"31;
"MHB_DATA3"
$PN"CD14"115;
"MHB_DATA17"
$PN"CR14"116;
"MHB_DATA28"
$PN"DD13"98;
"MHB_DQS_H0"
$PN"CD13"55;
"MHB_DQS_L4"
$PN"BW14"56;
"MHA_CA5"
$PN"BB13"32;
"MHA_DATA2"
$PN"F13"156;
"MHA_DQS_H5"
$PN"J14"67;
"MHA_DQS_L9"
$PN"AM14"57;
"MHB0_RSP_L"
$PN"BP13"22;
"MHB_CA4"
$PN"BJ14"33;
"MHB_CHECK7"
$PN"BV14"79;
"MHB_DATA2"
$PN"CC12"117;
"MHB_DATA16"
$PN"CP13"118;
"MHB_DATA27"
$PN"DB14"99;
"MHB_DQS_L3"
$PN"DC12"58;
"MHA_CA4"
$PN"BA12"34;
"MHA_DATA1"
$PN"F14"157;
"MHA_DQS_H4"
$PN"AL12"68;
"MHA_DQS_L8"
$PN"AF14"59;
"MHB_CA3"
$PN"BJ12"35;
"MHB_CHECK6"
$PN"BU12"80;
"MHB_DATA1"
$PN"CC14"119;
"MHB_DATA15"
$PN"CP14"120;
"MHB_DATA26"
$PN"DA12"100;
"MHB_DQS_L2"
$PN"CU12"60;
"MHA_CA3"
$PN"BA14"36;
"MHA_DATA0"
$PN"E12"158;
"MHA_DQS_H3"
$PN"AE12"69;
"MHA_DQS_L7"
$PN"Y14"70;
"MHB_CA2"
$PN"BH13"37;
"MHB_CHECK5"
$PN"BU14"81;
"MHB_DATA0"
$PN"CB13"134;
"MHB_DATA14"
$PN"CN12"121;
"MHB_DATA25"
$PN"DA14"101;
"MHB_DQS_L1"
$PN"CL12"61;
"MHA_CA2"
$PN"AY14"38;
"MHA_DATA19"
$PN"W14"135;
"MHA_DQS_H2"
$PN"W12"71;
"MHA_DQS_L6"
$PN"P14"72;
"MHB_CA1"
$PN"BH14"39;
"MHB_CHECK4"
$PN"BT13"82;
"MHB_DATA13"
$PN"CN14"122;
"MHB_DATA24"
$PN"CY13"102;
"MHB_DQS_L0"
$PN"CE12"62;
"MHA_CA1"
$PN"AY13"40;
"MHA_DATA18"
$PN"V13"136;
"MHA_DATA29"
$PN"AH14"137;
"MHA_DQS_H1"
$PN"N12"73;
"MHA_DQS_L5"
$PN"H14"74;
"MHB_CA0"
$PN"BG14"41;
"MHB_CHECK3"
$PN"CB14"83;
"MHB_DATA12"
$PN"CM13"123;
"MHB_DATA23"
$PN"CY14"103;
"MHA1_RSP_L"
$PN"BP14"0;
"MHA_CA0"
$PN"AW12"42;
"MHA_DATA17"
$PN"V14"138;
"MHA_DATA28"
$PN"AG12"139;
"MHA_DQS_H0"
$PN"G12"75;
"MHA_DQS_L4"
$PN"AM13"76;
"MHB_CHECK2"
$PN"CA12"84;
"MHB_DATA11"
$PN"CK14"124;
"MHB_DATA22"
$PN"CW12"104;
"MHA0_RSP_L"
$PN"BN14"18;
"MHA_CHECK7"
$PN"AR14"85;
"MHA_DATA16"
$PN"U12"140;
"MHA_DATA27"
$PN"AE14"141;
"MHA_DQS_L3"
$PN"AF13"77;
"MHB_CHECK1"
$PN"CA14"86;
"MHB_DATA10"
$PN"CJ12"125;
"MHB_DATA21"
$PN"CW14"105;
"MHA_CHECK6"
$PN"AP13"87;
"MHA_DATA15"
$PN"U14"142;
"MHA_DATA26"
$PN"AD13"143;
"MHA_DQS_L2"
$PN"Y13"78;
"MHB1_CS_L1"
$PN"BM13"0;
"MHB_CHECK0"
$PN"BY13"88;
"MHB_DATA20"
$PN"CV13"106;
"MHB_DATA31"
$PN"DF14"107;
"MH_RESET_L"
$PN"AU14"24;
"MH_ALERT_L"
$PN"AT14"13;
%"TAP"
"1","(-3350,5900)","0","mstr_standard","I161";
;
CDS_LIB"mstr_standard"
BODY_TYPE"PLUMBING"
HDL_TAP"TRUE";
"B \NAC \NWC"1;
"S \NAC"
BN"0"158;
%"TAP"
"1","(-3350,5800)","0","mstr_standard","I162";
;
CDS_LIB"mstr_standard"
BODY_TYPE"PLUMBING"
HDL_TAP"TRUE";
"B \NAC \NWC"1;
"S \NAC"
BN"2"156;
%"TAP"
"1","(-3350,5850)","0","mstr_standard","I163";
;
CDS_LIB"mstr_standard"
BODY_TYPE"PLUMBING"
HDL_TAP"TRUE";
"B \NAC \NWC"1;
"S \NAC"
BN"1"157;
%"TAP"
"1","(-3350,5750)","0","mstr_standard","I164";
;
CDS_LIB"mstr_standard"
BODY_TYPE"PLUMBING"
HDL_TAP"TRUE";
"B \NAC \NWC"1;
"S \NAC"
BN"3"155;
%"TAP"
"1","(-3350,5700)","0","mstr_standard","I165";
;
CDS_LIB"mstr_standard"
BODY_TYPE"PLUMBING"
HDL_TAP"TRUE";
"B \NAC \NWC"1;
"S \NAC"
BN"4"154;
%"TAP"
"1","(-3350,5650)","0","mstr_standard","I166";
;
CDS_LIB"mstr_standard"
BODY_TYPE"PLUMBING"
HDL_TAP"TRUE";
"B \NAC \NWC"1;
"S \NAC"
BN"5"153;
%"TAP"
"1","(-3350,5400)","0","mstr_standard","I167";
;
CDS_LIB"mstr_standard"
BODY_TYPE"PLUMBING"
HDL_TAP"TRUE";
"B \NAC \NWC"1;
"S \NAC"
BN"9"146;
%"TAP"
"1","(-3350,5550)","0","mstr_standard","I168";
;
CDS_LIB"mstr_standard"
BODY_TYPE"PLUMBING"
HDL_TAP"TRUE";
"B \NAC \NWC"1;
"S \NAC"
BN"7"150;
%"TAP"
"1","(-3350,5600)","0","mstr_standard","I169";
;
CDS_LIB"mstr_standard"
BODY_TYPE"PLUMBING"
HDL_TAP"TRUE";
"B \NAC \NWC"1;
"S \NAC"
BN"6"152;
%"TAP"
"1","(-3350,5450)","0","mstr_standard","I170";
;
CDS_LIB"mstr_standard"
BODY_TYPE"PLUMBING"
HDL_TAP"TRUE";
"B \NAC \NWC"1;
"S \NAC"
BN"8"148;
%"TAP"
"1","(-3350,5350)","0","mstr_standard","I171";
;
CDS_LIB"mstr_standard"
BODY_TYPE"PLUMBING"
HDL_TAP"TRUE";
"B \NAC \NWC"1;
"S \NAC"
BN"10"151;
%"TAP"
"1","(-3350,5250)","0","mstr_standard","I172";
;
CDS_LIB"mstr_standard"
BODY_TYPE"PLUMBING"
HDL_TAP"TRUE";
"B \NAC \NWC"1;
"S \NAC"
BN"12"147;
%"TAP"
"1","(-3350,5300)","0","mstr_standard","I173";
;
CDS_LIB"mstr_standard"
BODY_TYPE"PLUMBING"
HDL_TAP"TRUE";
"B \NAC \NWC"1;
"S \NAC"
BN"11"149;
%"TAP"
"1","(-3350,5150)","0","mstr_standard","I174";
;
CDS_LIB"mstr_standard"
BODY_TYPE"PLUMBING"
HDL_TAP"TRUE";
"B \NAC \NWC"1;
"S \NAC"
BN"14"144;
%"TAP"
"1","(-3350,5200)","0","mstr_standard","I175";
;
CDS_LIB"mstr_standard"
BODY_TYPE"PLUMBING"
HDL_TAP"TRUE";
"B \NAC \NWC"1;
"S \NAC"
BN"13"145;
%"TAP"
"1","(-3350,5000)","0","mstr_standard","I176";
;
CDS_LIB"mstr_standard"
BODY_TYPE"PLUMBING"
HDL_TAP"TRUE";
"B \NAC \NWC"1;
"S \NAC"
BN"16"140;
%"TAP"
"1","(-3350,5100)","0","mstr_standard","I177";
;
CDS_LIB"mstr_standard"
BODY_TYPE"PLUMBING"
HDL_TAP"TRUE";
"B \NAC \NWC"1;
"S \NAC"
BN"15"142;
%"TAP"
"1","(-3350,4900)","0","mstr_standard","I178";
;
CDS_LIB"mstr_standard"
BODY_TYPE"PLUMBING"
HDL_TAP"TRUE";
"B \NAC \NWC"1;
"S \NAC"
BN"18"136;
%"TAP"
"1","(-3350,4950)","0","mstr_standard","I179";
;
CDS_LIB"mstr_standard"
BODY_TYPE"PLUMBING"
HDL_TAP"TRUE";
"B \NAC \NWC"1;
"S \NAC"
BN"17"138;
%"TAP"
"1","(-3350,4800)","0","mstr_standard","I180";
;
CDS_LIB"mstr_standard"
BODY_TYPE"PLUMBING"
HDL_TAP"TRUE";
"B \NAC \NWC"1;
"S \NAC"
BN"20"131;
%"TAP"
"1","(-3350,4850)","0","mstr_standard","I181";
;
CDS_LIB"mstr_standard"
BODY_TYPE"PLUMBING"
HDL_TAP"TRUE";
"B \NAC \NWC"1;
"S \NAC"
BN"19"135;
%"TAP"
"1","(-3350,4750)","0","mstr_standard","I182";
;
CDS_LIB"mstr_standard"
BODY_TYPE"PLUMBING"
HDL_TAP"TRUE";
"B \NAC \NWC"1;
"S \NAC"
BN"21"130;
%"TAP"
"1","(-3350,4650)","0","mstr_standard","I183";
;
CDS_LIB"mstr_standard"
BODY_TYPE"PLUMBING"
HDL_TAP"TRUE";
"B \NAC \NWC"1;
"S \NAC"
BN"23"128;
%"TAP"
"1","(-3350,4700)","0","mstr_standard","I184";
;
CDS_LIB"mstr_standard"
BODY_TYPE"PLUMBING"
HDL_TAP"TRUE";
"B \NAC \NWC"1;
"S \NAC"
BN"22"129;
%"TAP"
"1","(-3350,4550)","0","mstr_standard","I185";
;
CDS_LIB"mstr_standard"
BODY_TYPE"PLUMBING"
HDL_TAP"TRUE";
"B \NAC \NWC"1;
"S \NAC"
BN"24"127;
%"TAP"
"1","(-3350,4500)","0","mstr_standard","I186";
;
CDS_LIB"mstr_standard"
BODY_TYPE"PLUMBING"
HDL_TAP"TRUE";
"B \NAC \NWC"1;
"S \NAC"
BN"25"126;
%"TAP"
"1","(-3350,4400)","0","mstr_standard","I187";
;
CDS_LIB"mstr_standard"
BODY_TYPE"PLUMBING"
HDL_TAP"TRUE";
"B \NAC \NWC"1;
"S \NAC"
BN"27"141;
%"TAP"
"1","(-3350,4450)","0","mstr_standard","I188";
;
CDS_LIB"mstr_standard"
BODY_TYPE"PLUMBING"
HDL_TAP"TRUE";
"B \NAC \NWC"1;
"S \NAC"
BN"26"143;
%"TAP"
"1","(-3350,4300)","0","mstr_standard","I189";
;
CDS_LIB"mstr_standard"
BODY_TYPE"PLUMBING"
HDL_TAP"TRUE";
"B \NAC \NWC"1;
"S \NAC"
BN"29"137;
%"TAP"
"1","(-3350,4350)","0","mstr_standard","I190";
;
CDS_LIB"mstr_standard"
BODY_TYPE"PLUMBING"
HDL_TAP"TRUE";
"B \NAC \NWC"1;
"S \NAC"
BN"28"139;
%"TAP"
"1","(-3350,4250)","0","mstr_standard","I191";
;
CDS_LIB"mstr_standard"
BODY_TYPE"PLUMBING"
HDL_TAP"TRUE";
"B \NAC \NWC"1;
"S \NAC"
BN"30"133;
%"TAP"
"1","(-3350,4100)","0","mstr_standard","I192";
;
CDS_LIB"mstr_standard"
BODY_TYPE"PLUMBING"
HDL_TAP"TRUE";
"B \NAC \NWC"2;
"S \NAC"
BN"0"134;
%"TAP"
"1","(-3350,4200)","0","mstr_standard","I193";
;
CDS_LIB"mstr_standard"
BODY_TYPE"PLUMBING"
HDL_TAP"TRUE";
"B \NAC \NWC"1;
"S \NAC"
BN"31"132;
%"TAP"
"1","(-3350,4000)","0","mstr_standard","I196";
;
CDS_LIB"mstr_standard"
BODY_TYPE"PLUMBING"
HDL_TAP"TRUE";
"B \NAC \NWC"2;
"S \NAC"
BN"2"117;
%"TAP"
"1","(-3350,4050)","0","mstr_standard","I197";
;
CDS_LIB"mstr_standard"
BODY_TYPE"PLUMBING"
HDL_TAP"TRUE";
"B \NAC \NWC"2;
"S \NAC"
BN"1"119;
%"TAP"
"1","(-3350,3950)","0","mstr_standard","I198";
;
CDS_LIB"mstr_standard"
BODY_TYPE"PLUMBING"
HDL_TAP"TRUE";
"B \NAC \NWC"2;
"S \NAC"
BN"3"115;
%"TAP"
"1","(-3350,3900)","0","mstr_standard","I199";
;
CDS_LIB"mstr_standard"
BODY_TYPE"PLUMBING"
HDL_TAP"TRUE";
"B \NAC \NWC"2;
"S \NAC"
BN"4"113;
%"TAP"
"1","(-3350,3850)","0","mstr_standard","I200";
;
CDS_LIB"mstr_standard"
BODY_TYPE"PLUMBING"
HDL_TAP"TRUE";
"B \NAC \NWC"2;
"S \NAC"
BN"5"112;
%"TAP"
"1","(-3350,3750)","0","mstr_standard","I201";
;
CDS_LIB"mstr_standard"
BODY_TYPE"PLUMBING"
HDL_TAP"TRUE";
"B \NAC \NWC"2;
"S \NAC"
BN"7"110;
%"TAP"
"1","(-3350,3650)","0","mstr_standard","I202";
;
CDS_LIB"mstr_standard"
BODY_TYPE"PLUMBING"
HDL_TAP"TRUE";
"B \NAC \NWC"2;
"S \NAC"
BN"8"109;
%"TAP"
"1","(-3350,3800)","0","mstr_standard","I203";
;
CDS_LIB"mstr_standard"
BODY_TYPE"PLUMBING"
HDL_TAP"TRUE";
"B \NAC \NWC"2;
"S \NAC"
BN"6"111;
%"TAP"
"1","(-3350,3600)","0","mstr_standard","I204";
;
CDS_LIB"mstr_standard"
BODY_TYPE"PLUMBING"
HDL_TAP"TRUE";
"B \NAC \NWC"2;
"S \NAC"
BN"9"108;
%"TAP"
"1","(-3350,3550)","0","mstr_standard","I205";
;
CDS_LIB"mstr_standard"
BODY_TYPE"PLUMBING"
HDL_TAP"TRUE";
"B \NAC \NWC"2;
"S \NAC"
BN"10"125;
%"TAP"
"1","(-3350,3500)","0","mstr_standard","I206";
;
CDS_LIB"mstr_standard"
BODY_TYPE"PLUMBING"
HDL_TAP"TRUE";
"B \NAC \NWC"2;
"S \NAC"
BN"11"124;
%"TAP"
"1","(-3350,3350)","0","mstr_standard","I207";
;
CDS_LIB"mstr_standard"
BODY_TYPE"PLUMBING"
HDL_TAP"TRUE";
"B \NAC \NWC"2;
"S \NAC"
BN"14"121;
%"TAP"
"1","(-3350,3400)","0","mstr_standard","I208";
;
CDS_LIB"mstr_standard"
BODY_TYPE"PLUMBING"
HDL_TAP"TRUE";
"B \NAC \NWC"2;
"S \NAC"
BN"13"122;
%"TAP"
"1","(-3350,3450)","0","mstr_standard","I209";
;
CDS_LIB"mstr_standard"
BODY_TYPE"PLUMBING"
HDL_TAP"TRUE";
"B \NAC \NWC"2;
"S \NAC"
BN"12"123;
%"TAP"
"1","(-3350,3150)","0","mstr_standard","I210";
;
CDS_LIB"mstr_standard"
BODY_TYPE"PLUMBING"
HDL_TAP"TRUE";
"B \NAC \NWC"2;
"S \NAC"
BN"17"116;
%"TAP"
"1","(-3350,3200)","0","mstr_standard","I211";
;
CDS_LIB"mstr_standard"
BODY_TYPE"PLUMBING"
HDL_TAP"TRUE";
"B \NAC \NWC"2;
"S \NAC"
BN"16"118;
%"TAP"
"1","(-3350,3300)","0","mstr_standard","I212";
;
CDS_LIB"mstr_standard"
BODY_TYPE"PLUMBING"
HDL_TAP"TRUE";
"B \NAC \NWC"2;
"S \NAC"
BN"15"120;
%"TAP"
"1","(-3350,3100)","0","mstr_standard","I213";
;
CDS_LIB"mstr_standard"
BODY_TYPE"PLUMBING"
HDL_TAP"TRUE";
"B \NAC \NWC"2;
"S \NAC"
BN"18"114;
%"TAP"
"1","(-3350,2950)","0","mstr_standard","I214";
;
CDS_LIB"mstr_standard"
BODY_TYPE"PLUMBING"
HDL_TAP"TRUE";
"B \NAC \NWC"2;
"S \NAC"
BN"21"105;
%"TAP"
"1","(-3350,3050)","0","mstr_standard","I215";
;
CDS_LIB"mstr_standard"
BODY_TYPE"PLUMBING"
HDL_TAP"TRUE";
"B \NAC \NWC"2;
"S \NAC"
BN"19"96;
%"TAP"
"1","(-3350,3000)","0","mstr_standard","I216";
;
CDS_LIB"mstr_standard"
BODY_TYPE"PLUMBING"
HDL_TAP"TRUE";
"B \NAC \NWC"2;
"S \NAC"
BN"20"106;
%"TAP"
"1","(-3350,2850)","0","mstr_standard","I217";
;
CDS_LIB"mstr_standard"
BODY_TYPE"PLUMBING"
HDL_TAP"TRUE";
"B \NAC \NWC"2;
"S \NAC"
BN"23"103;
%"TAP"
"1","(-3350,2900)","0","mstr_standard","I218";
;
CDS_LIB"mstr_standard"
BODY_TYPE"PLUMBING"
HDL_TAP"TRUE";
"B \NAC \NWC"2;
"S \NAC"
BN"22"104;
%"TAP"
"1","(-3350,2650)","0","mstr_standard","I219";
;
CDS_LIB"mstr_standard"
BODY_TYPE"PLUMBING"
HDL_TAP"TRUE";
"B \NAC \NWC"2;
"S \NAC"
BN"26"100;
%"TAP"
"1","(-3350,2700)","0","mstr_standard","I220";
;
CDS_LIB"mstr_standard"
BODY_TYPE"PLUMBING"
HDL_TAP"TRUE";
"B \NAC \NWC"2;
"S \NAC"
BN"25"101;
%"TAP"
"1","(-3350,2750)","0","mstr_standard","I221";
;
CDS_LIB"mstr_standard"
BODY_TYPE"PLUMBING"
HDL_TAP"TRUE";
"B \NAC \NWC"2;
"S \NAC"
BN"24"102;
%"TAP"
"1","(-3350,2600)","0","mstr_standard","I222";
;
CDS_LIB"mstr_standard"
BODY_TYPE"PLUMBING"
HDL_TAP"TRUE";
"B \NAC \NWC"2;
"S \NAC"
BN"27"99;
%"TAP"
"1","(-3350,2400)","0","mstr_standard","I223";
;
CDS_LIB"mstr_standard"
BODY_TYPE"PLUMBING"
HDL_TAP"TRUE";
"B \NAC \NWC"2;
"S \NAC"
BN"31"107;
%"TAP"
"1","(-3350,2550)","0","mstr_standard","I224";
;
CDS_LIB"mstr_standard"
BODY_TYPE"PLUMBING"
HDL_TAP"TRUE";
"B \NAC \NWC"2;
"S \NAC"
BN"28"98;
%"TAP"
"1","(-3350,2500)","0","mstr_standard","I225";
;
CDS_LIB"mstr_standard"
BODY_TYPE"PLUMBING"
HDL_TAP"TRUE";
"B \NAC \NWC"2;
"S \NAC"
BN"29"97;
%"TAP"
"1","(-3350,2450)","0","mstr_standard","I226";
;
CDS_LIB"mstr_standard"
BODY_TYPE"PLUMBING"
HDL_TAP"TRUE";
"B \NAC \NWC"2;
"S \NAC"
BN"30"90;
%"TAP"
"1","(-3350,2250)","0","mstr_standard","I227";
;
CDS_LIB"mstr_standard"
BODY_TYPE"PLUMBING"
HDL_TAP"TRUE";
"B \NAC \NWC"3;
"S \NAC"
BN"1"94;
%"TAP"
"1","(-3350,2300)","0","mstr_standard","I228";
;
CDS_LIB"mstr_standard"
BODY_TYPE"PLUMBING"
HDL_TAP"TRUE";
"B \NAC \NWC"3;
"S \NAC"
BN"0"95;
%"TAP"
"1","(-3350,2200)","0","mstr_standard","I229";
;
CDS_LIB"mstr_standard"
BODY_TYPE"PLUMBING"
HDL_TAP"TRUE";
"B \NAC \NWC"3;
"S \NAC"
BN"2"93;
%"TAP"
"1","(-3350,2150)","0","mstr_standard","I230";
;
CDS_LIB"mstr_standard"
BODY_TYPE"PLUMBING"
HDL_TAP"TRUE";
"B \NAC \NWC"3;
"S \NAC"
BN"3"92;
%"TAP"
"1","(-3350,2050)","0","mstr_standard","I231";
;
CDS_LIB"mstr_standard"
BODY_TYPE"PLUMBING"
HDL_TAP"TRUE";
"B \NAC \NWC"3;
"S \NAC"
BN"5"89;
%"TAP"
"1","(-3350,2100)","0","mstr_standard","I232";
;
CDS_LIB"mstr_standard"
BODY_TYPE"PLUMBING"
HDL_TAP"TRUE";
"B \NAC \NWC"3;
"S \NAC"
BN"4"91;
%"TAP"
"1","(-3350,1950)","0","mstr_standard","I234";
;
CDS_LIB"mstr_standard"
BODY_TYPE"PLUMBING"
HDL_TAP"TRUE";
"B \NAC \NWC"3;
"S \NAC"
BN"7"85;
%"TAP"
"1","(-3350,1850)","0","mstr_standard","I235";
;
CDS_LIB"mstr_standard"
BODY_TYPE"PLUMBING"
HDL_TAP"TRUE";
"B \NAC \NWC"4;
"S \NAC"
BN"0"88;
%"TAP"
"1","(-3350,2000)","0","mstr_standard","I236";
;
CDS_LIB"mstr_standard"
BODY_TYPE"PLUMBING"
HDL_TAP"TRUE";
"B \NAC \NWC"3;
"S \NAC"
BN"6"87;
%"TAP"
"1","(-3350,1800)","0","mstr_standard","I237";
;
CDS_LIB"mstr_standard"
BODY_TYPE"PLUMBING"
HDL_TAP"TRUE";
"B \NAC \NWC"4;
"S \NAC"
BN"1"86;
%"TAP"
"1","(-3350,1750)","0","mstr_standard","I238";
;
CDS_LIB"mstr_standard"
BODY_TYPE"PLUMBING"
HDL_TAP"TRUE";
"B \NAC \NWC"4;
"S \NAC"
BN"2"84;
%"TAP"
"1","(-3350,1700)","0","mstr_standard","I239";
;
CDS_LIB"mstr_standard"
BODY_TYPE"PLUMBING"
HDL_TAP"TRUE";
"B \NAC \NWC"4;
"S \NAC"
BN"3"83;
%"TAP"
"1","(-3350,1600)","0","mstr_standard","I240";
;
CDS_LIB"mstr_standard"
BODY_TYPE"PLUMBING"
HDL_TAP"TRUE";
"B \NAC \NWC"4;
"S \NAC"
BN"5"81;
%"TAP"
"1","(-3350,1550)","0","mstr_standard","I241";
;
CDS_LIB"mstr_standard"
BODY_TYPE"PLUMBING"
HDL_TAP"TRUE";
"B \NAC \NWC"4;
"S \NAC"
BN"6"80;
%"TAP"
"1","(-3350,1650)","0","mstr_standard","I242";
;
CDS_LIB"mstr_standard"
BODY_TYPE"PLUMBING"
HDL_TAP"TRUE";
"B \NAC \NWC"4;
"S \NAC"
BN"4"82;
%"TAP"
"1","(-3350,1500)","0","mstr_standard","I243";
;
CDS_LIB"mstr_standard"
BODY_TYPE"PLUMBING"
HDL_TAP"TRUE";
"B \NAC \NWC"4;
"S \NAC"
BN"7"79;
%"TAP"
"1","(-5775,5900)","2","mstr_standard","I244";
;
CDS_LIB"mstr_standard"
BODY_TYPE"PLUMBING"
HDL_TAP"TRUE";
"B \NAC \NWC"5;
"S \NAC"
BN"0"75;
%"TAP"
"1","(-5775,5800)","2","mstr_standard","I245";
;
CDS_LIB"mstr_standard"
BODY_TYPE"PLUMBING"
HDL_TAP"TRUE";
"B \NAC \NWC"5;
"S \NAC"
BN"1"73;
%"TAP"
"1","(-5775,5700)","2","mstr_standard","I246";
;
CDS_LIB"mstr_standard"
BODY_TYPE"PLUMBING"
HDL_TAP"TRUE";
"B \NAC \NWC"5;
"S \NAC"
BN"2"71;
%"TAP"
"1","(-5975,5650)","2","mstr_standard","I247";
;
CDS_LIB"mstr_standard"
BODY_TYPE"PLUMBING"
HDL_TAP"TRUE";
"B \NAC \NWC"9;
"S \NAC"
BN"2"78;
%"TAP"
"1","(-5975,5750)","2","mstr_standard","I248";
;
CDS_LIB"mstr_standard"
BODY_TYPE"PLUMBING"
HDL_TAP"TRUE";
"B \NAC \NWC"9;
"S \NAC"
BN"1"63;
%"TAP"
"1","(-5975,5850)","2","mstr_standard","I249";
;
CDS_LIB"mstr_standard"
BODY_TYPE"PLUMBING"
HDL_TAP"TRUE";
"B \NAC \NWC"9;
"S \NAC"
BN"0"64;
%"TAP"
"1","(-5775,5600)","2","mstr_standard","I250";
;
CDS_LIB"mstr_standard"
BODY_TYPE"PLUMBING"
HDL_TAP"TRUE";
"B \NAC \NWC"5;
"S \NAC"
BN"3"69;
%"TAP"
"1","(-5775,5500)","2","mstr_standard","I251";
;
CDS_LIB"mstr_standard"
BODY_TYPE"PLUMBING"
HDL_TAP"TRUE";
"B \NAC \NWC"5;
"S \NAC"
BN"4"68;
%"TAP"
"1","(-5775,5400)","2","mstr_standard","I252";
;
CDS_LIB"mstr_standard"
BODY_TYPE"PLUMBING"
HDL_TAP"TRUE";
"B \NAC \NWC"5;
"S \NAC"
BN"5"67;
%"TAP"
"1","(-5775,5300)","2","mstr_standard","I253";
;
CDS_LIB"mstr_standard"
BODY_TYPE"PLUMBING"
HDL_TAP"TRUE";
"B \NAC \NWC"5;
"S \NAC"
BN"6"66;
%"TAP"
"1","(-5775,5200)","2","mstr_standard","I254";
;
CDS_LIB"mstr_standard"
BODY_TYPE"PLUMBING"
HDL_TAP"TRUE";
"B \NAC \NWC"5;
"S \NAC"
BN"7"65;
%"TAP"
"1","(-5975,5550)","2","mstr_standard","I255";
;
CDS_LIB"mstr_standard"
BODY_TYPE"PLUMBING"
HDL_TAP"TRUE";
"B \NAC \NWC"9;
"S \NAC"
BN"3"77;
%"TAP"
"1","(-5975,5450)","2","mstr_standard","I256";
;
CDS_LIB"mstr_standard"
BODY_TYPE"PLUMBING"
HDL_TAP"TRUE";
"B \NAC \NWC"9;
"S \NAC"
BN"4"76;
%"TAP"
"1","(-5975,5350)","2","mstr_standard","I257";
;
CDS_LIB"mstr_standard"
BODY_TYPE"PLUMBING"
HDL_TAP"TRUE";
"B \NAC \NWC"9;
"S \NAC"
BN"5"74;
%"TAP"
"1","(-5975,5250)","2","mstr_standard","I258";
;
CDS_LIB"mstr_standard"
BODY_TYPE"PLUMBING"
HDL_TAP"TRUE";
"B \NAC \NWC"9;
"S \NAC"
BN"6"72;
%"TAP"
"1","(-5975,5150)","2","mstr_standard","I259";
;
CDS_LIB"mstr_standard"
BODY_TYPE"PLUMBING"
HDL_TAP"TRUE";
"B \NAC \NWC"9;
"S \NAC"
BN"7"70;
%"TAP"
"1","(-5775,5100)","2","mstr_standard","I260";
;
CDS_LIB"mstr_standard"
BODY_TYPE"PLUMBING"
HDL_TAP"TRUE";
"B \NAC \NWC"5;
"S \NAC"
BN"8"50;
%"TAP"
"1","(-5775,5000)","2","mstr_standard","I261";
;
CDS_LIB"mstr_standard"
BODY_TYPE"PLUMBING"
HDL_TAP"TRUE";
"B \NAC \NWC"5;
"S \NAC"
BN"9"47;
%"TAP"
"1","(-5775,4850)","2","mstr_standard","I262";
;
CDS_LIB"mstr_standard"
BODY_TYPE"PLUMBING"
HDL_TAP"TRUE";
"B \NAC \NWC"6;
"S \NAC"
BN"0"55;
%"TAP"
"1","(-5775,4750)","2","mstr_standard","I263";
;
CDS_LIB"mstr_standard"
BODY_TYPE"PLUMBING"
HDL_TAP"TRUE";
"B \NAC \NWC"6;
"S \NAC"
BN"1"53;
%"TAP"
"1","(-5775,4650)","2","mstr_standard","I264";
;
CDS_LIB"mstr_standard"
BODY_TYPE"PLUMBING"
HDL_TAP"TRUE";
"B \NAC \NWC"6;
"S \NAC"
BN"2"51;
%"TAP"
"1","(-5975,5050)","2","mstr_standard","I265";
;
CDS_LIB"mstr_standard"
BODY_TYPE"PLUMBING"
HDL_TAP"TRUE";
"B \NAC \NWC"9;
"S \NAC"
BN"8"59;
%"TAP"
"1","(-5975,4950)","2","mstr_standard","I266";
;
CDS_LIB"mstr_standard"
BODY_TYPE"PLUMBING"
HDL_TAP"TRUE";
"B \NAC \NWC"9;
"S \NAC"
BN"9"57;
%"TAP"
"1","(-5975,4800)","2","mstr_standard","I267";
;
CDS_LIB"mstr_standard"
BODY_TYPE"PLUMBING"
HDL_TAP"TRUE";
"B \NAC \NWC"10;
"S \NAC"
BN"0"62;
%"TAP"
"1","(-5975,4700)","2","mstr_standard","I268";
;
CDS_LIB"mstr_standard"
BODY_TYPE"PLUMBING"
HDL_TAP"TRUE";
"B \NAC \NWC"10;
"S \NAC"
BN"1"61;
%"TAP"
"1","(-5775,4550)","2","mstr_standard","I269";
;
CDS_LIB"mstr_standard"
BODY_TYPE"PLUMBING"
HDL_TAP"TRUE";
"B \NAC \NWC"6;
"S \NAC"
BN"3"48;
%"TAP"
"1","(-5775,4450)","2","mstr_standard","I270";
;
CDS_LIB"mstr_standard"
BODY_TYPE"PLUMBING"
HDL_TAP"TRUE";
"B \NAC \NWC"6;
"S \NAC"
BN"4"46;
%"TAP"
"1","(-5975,4600)","2","mstr_standard","I271";
;
CDS_LIB"mstr_standard"
BODY_TYPE"PLUMBING"
HDL_TAP"TRUE";
"B \NAC \NWC"10;
"S \NAC"
BN"2"60;
%"TAP"
"1","(-5775,4350)","2","mstr_standard","I272";
;
CDS_LIB"mstr_standard"
BODY_TYPE"PLUMBING"
HDL_TAP"TRUE";
"B \NAC \NWC"6;
"S \NAC"
BN"5"45;
%"TAP"
"1","(-5775,4250)","2","mstr_standard","I273";
;
CDS_LIB"mstr_standard"
BODY_TYPE"PLUMBING"
HDL_TAP"TRUE";
"B \NAC \NWC"6;
"S \NAC"
BN"6"44;
%"TAP"
"1","(-5775,4150)","2","mstr_standard","I274";
;
CDS_LIB"mstr_standard"
BODY_TYPE"PLUMBING"
HDL_TAP"TRUE";
"B \NAC \NWC"6;
"S \NAC"
BN"7"43;
%"TAP"
"1","(-5975,4500)","2","mstr_standard","I275";
;
CDS_LIB"mstr_standard"
BODY_TYPE"PLUMBING"
HDL_TAP"TRUE";
"B \NAC \NWC"10;
"S \NAC"
BN"3"58;
%"TAP"
"1","(-5975,4400)","2","mstr_standard","I276";
;
CDS_LIB"mstr_standard"
BODY_TYPE"PLUMBING"
HDL_TAP"TRUE";
"B \NAC \NWC"10;
"S \NAC"
BN"4"56;
%"TAP"
"1","(-5975,4300)","2","mstr_standard","I277";
;
CDS_LIB"mstr_standard"
BODY_TYPE"PLUMBING"
HDL_TAP"TRUE";
"B \NAC \NWC"10;
"S \NAC"
BN"5"54;
%"TAP"
"1","(-5975,4200)","2","mstr_standard","I278";
;
CDS_LIB"mstr_standard"
BODY_TYPE"PLUMBING"
HDL_TAP"TRUE";
"B \NAC \NWC"10;
"S \NAC"
BN"6"52;
%"TAP"
"1","(-5975,4100)","2","mstr_standard","I279";
;
CDS_LIB"mstr_standard"
BODY_TYPE"PLUMBING"
HDL_TAP"TRUE";
"B \NAC \NWC"10;
"S \NAC"
BN"7"49;
%"TAP"
"1","(-5775,4050)","2","mstr_standard","I284";
;
CDS_LIB"mstr_standard"
BODY_TYPE"PLUMBING"
HDL_TAP"TRUE";
"B \NAC \NWC"6;
"S \NAC"
BN"8"27;
%"TAP"
"1","(-5775,3950)","2","mstr_standard","I285";
;
CDS_LIB"mstr_standard"
BODY_TYPE"PLUMBING"
HDL_TAP"TRUE";
"B \NAC \NWC"6;
"S \NAC"
BN"9"26;
%"TAP"
"1","(-5975,4000)","2","mstr_standard","I286";
;
CDS_LIB"mstr_standard"
BODY_TYPE"PLUMBING"
HDL_TAP"TRUE";
"B \NAC \NWC"10;
"S \NAC"
BN"8"29;
%"TAP"
"1","(-5975,3900)","2","mstr_standard","I287";
;
CDS_LIB"mstr_standard"
BODY_TYPE"PLUMBING"
HDL_TAP"TRUE";
"B \NAC \NWC"10;
"S \NAC"
BN"9"28;
%"TAP"
"1","(-5975,3750)","2","mstr_standard","I288";
;
CDS_LIB"mstr_standard"
BODY_TYPE"PLUMBING"
HDL_TAP"TRUE";
"B \NAC \NWC"7;
"S \NAC"
BN"0"42;
%"TAP"
"1","(-5975,3700)","2","mstr_standard","I289";
;
CDS_LIB"mstr_standard"
BODY_TYPE"PLUMBING"
HDL_TAP"TRUE";
"B \NAC \NWC"7;
"S \NAC"
BN"1"40;
%"TAP"
"1","(-5975,3650)","2","mstr_standard","I290";
;
CDS_LIB"mstr_standard"
BODY_TYPE"PLUMBING"
HDL_TAP"TRUE";
"B \NAC \NWC"7;
"S \NAC"
BN"2"38;
%"TAP"
"1","(-5975,3600)","2","mstr_standard","I291";
;
CDS_LIB"mstr_standard"
BODY_TYPE"PLUMBING"
HDL_TAP"TRUE";
"B \NAC \NWC"7;
"S \NAC"
BN"3"36;
%"TAP"
"1","(-5975,3500)","2","mstr_standard","I292";
;
CDS_LIB"mstr_standard"
BODY_TYPE"PLUMBING"
HDL_TAP"TRUE";
"B \NAC \NWC"7;
"S \NAC"
BN"5"32;
%"TAP"
"1","(-5975,3550)","2","mstr_standard","I293";
;
CDS_LIB"mstr_standard"
BODY_TYPE"PLUMBING"
HDL_TAP"TRUE";
"B \NAC \NWC"7;
"S \NAC"
BN"4"34;
%"TAP"
"1","(-5975,3450)","2","mstr_standard","I294";
;
CDS_LIB"mstr_standard"
BODY_TYPE"PLUMBING"
HDL_TAP"TRUE";
"B \NAC \NWC"7;
"S \NAC"
BN"6"30;
%"TAP"
"1","(-5975,3350)","2","mstr_standard","I295";
;
CDS_LIB"mstr_standard"
BODY_TYPE"PLUMBING"
HDL_TAP"TRUE";
"B \NAC \NWC"8;
"S \NAC"
BN"0"41;
%"TAP"
"1","(-5975,3250)","2","mstr_standard","I296";
;
CDS_LIB"mstr_standard"
BODY_TYPE"PLUMBING"
HDL_TAP"TRUE";
"B \NAC \NWC"8;
"S \NAC"
BN"2"37;
%"TAP"
"1","(-5975,3300)","2","mstr_standard","I297";
;
CDS_LIB"mstr_standard"
BODY_TYPE"PLUMBING"
HDL_TAP"TRUE";
"B \NAC \NWC"8;
"S \NAC"
BN"1"39;
%"TAP"
"1","(-5975,3200)","2","mstr_standard","I298";
;
CDS_LIB"mstr_standard"
BODY_TYPE"PLUMBING"
HDL_TAP"TRUE";
"B \NAC \NWC"8;
"S \NAC"
BN"3"35;
%"TAP"
"1","(-5975,3100)","2","mstr_standard","I299";
;
CDS_LIB"mstr_standard"
BODY_TYPE"PLUMBING"
HDL_TAP"TRUE";
"B \NAC \NWC"8;
"S \NAC"
BN"5"31;
%"TAP"
"1","(-5975,3150)","2","mstr_standard","I300";
;
CDS_LIB"mstr_standard"
BODY_TYPE"PLUMBING"
HDL_TAP"TRUE";
"B \NAC \NWC"8;
"S \NAC"
BN"4"33;
%"TAP"
"1","(-5975,3050)","2","mstr_standard","I301";
;
CDS_LIB"mstr_standard"
BODY_TYPE"PLUMBING"
HDL_TAP"TRUE";
"B \NAC \NWC"8;
"S \NAC"
BN"6"25;
%"Q_RES"
"1","(-6650,2050)","0","pure_quanta","I314";
;
LOCATION"R507"
$SEC"1"
CDS_SEC"1"
TOLERANCE"1%"
VALUE"15   "
PART_NUMBER"CS01502FB11"
PACK_TYPE"0402LF"
CDS_LIB"pure_quanta"
WATTAGE"1/16W"
MATERIAL"CHIP";
"B"
$PN"2"13;
"A"
$PN"1"11;
END.
